(kicad_pcb
	(version 20260206)
	(generator "pcbnew")
	(generator_version "10.0")
	(general
		(thickness 1.6)
		(legacy_teardrops no)
	)
	(paper "A4")
	(title_block
		(title "01162023_DA0F0TEBIF0_F0T_Expander_BD_F_brd_V02_OCP.brd")
		(comment 1 "Grand Teton / footprints 8324-8330 of 9728")
	)
	(layers
		(0 "F.Cu" signal "TOP")
		(4 "In1.Cu" signal "GND")
		(6 "In2.Cu" signal "VCC")
		(8 "In3.Cu" signal "VCC1")
		(10 "In4.Cu" signal "GND1")
		(12 "In5.Cu" signal "IN1")
		(14 "In6.Cu" signal "GND2")
		(16 "In7.Cu" signal "IN2")
		(18 "In8.Cu" signal "GND3")
		(20 "In9.Cu" signal "IN3")
		(22 "In10.Cu" signal "GND4")
		(24 "In11.Cu" signal "IN4")
		(26 "In12.Cu" signal "GND5")
		(28 "In13.Cu" signal "IN5")
		(30 "In14.Cu" signal "GND6")
		(32 "In15.Cu" signal "IN6")
		(34 "In16.Cu" signal "GND7")
		(2 "B.Cu" signal "BOTTOM")
		(9 "F.Adhes" user "F.Adhesive")
		(11 "B.Adhes" user "B.Adhesive")
		(13 "F.Paste" user "Package Geometry/Pastemask Top")
		(15 "B.Paste" user "Package Geometry/Pastemask Bottom")
		(5 "F.SilkS" user "Ref Des/Silkscreen Top")
		(7 "B.SilkS" user "Ref Des/Silkscreen Bottom")
		(1 "F.Mask" user "Board Geometry/Soldermask Top")
		(3 "B.Mask" user "Board Geometry/Soldermask Bottom")
		(17 "Dwgs.User" user "User.Drawings")
		(19 "Cmts.User" user "User.Comments")
		(21 "Eco1.User" user "User.Eco1")
		(23 "Eco2.User" user "User.Eco2")
		(25 "Edge.Cuts" user "Board Geometry/Outline")
		(27 "Margin" user)
		(31 "F.CrtYd" user "Package Geometry/Place Bound Top")
		(29 "B.CrtYd" user "Package Geometry/Place Bound Bottom")
		(35 "F.Fab" user "Ref Des/Assembly Top")
		(33 "B.Fab" user "Ref Des/Assembly Bottom")
	)
	(footprint ""
		(layer "B.Cu")
		(at 114.649758 -321.385438 -90)
		(property "Reference" "R6455"
			(at 0 0 90)
			(layer "B.SilkS")
			(hide yes)
			(effects
				(font
					(size 1.27 1.27)
				)
				(justify mirror)
			)
		)
		(property "Value" ""
			(at 0 0 90)
			(layer "B.Fab")
			(effects
				(font
					(size 1.27 1.27)
				)
				(justify mirror)
			)
		)
		(duplicate_pad_numbers_are_jumpers no)
		(fp_line
			(start -0.7874 0.4064)
			(end 0.7874 0.4064)
			(stroke
				(width 0.1524)
				(type default)
			)
			(layer "B.SilkS")
		)
		(fp_line
			(start 0.7874 0.4064)
			(end 0.7874 -0.4064)
			(stroke
				(width 0.1524)
				(type default)
			)
			(layer "B.SilkS")
		)
		(fp_line
			(start -0.7874 -0.4064)
			(end -0.7874 0.4064)
			(stroke
				(width 0.1524)
				(type default)
			)
			(layer "B.SilkS")
		)
		(fp_line
			(start 0.7874 -0.4064)
			(end -0.7874 -0.4064)
			(stroke
				(width 0.1524)
				(type default)
			)
			(layer "B.SilkS")
		)
		(fp_line
			(start -0.67945 0.3048)
			(end -0.120396 0.3048)
			(stroke
				(width 0.1)
				(type default)
			)
			(layer "B.Fab")
		)
		(fp_line
			(start -0.120396 0.3048)
			(end -0.120396 0.2794)
			(stroke
				(width 0.1)
				(type default)
			)
			(layer "B.Fab")
		)
		(fp_line
			(start 0.12065 0.3048)
			(end 0.67945 0.3048)
			(stroke
				(width 0.1)
				(type default)
			)
			(layer "B.Fab")
		)
		(fp_line
			(start 0.67945 0.3048)
			(end 0.67945 -0.305054)
			(stroke
				(width 0.1)
				(type default)
			)
			(layer "B.Fab")
		)
		(fp_line
			(start -0.120396 0.2794)
			(end 0.12065 0.2794)
			(stroke
				(width 0.1)
				(type default)
			)
			(layer "B.Fab")
		)
		(fp_line
			(start 0.12065 0.2794)
			(end 0.12065 0.3048)
			(stroke
				(width 0.1)
				(type default)
			)
			(layer "B.Fab")
		)
		(fp_line
			(start -0.12065 -0.2794)
			(end -0.12065 -0.3048)
			(stroke
				(width 0.1)
				(type default)
			)
			(layer "B.Fab")
		)
		(fp_line
			(start 0.12065 -0.2794)
			(end -0.12065 -0.2794)
			(stroke
				(width 0.1)
				(type default)
			)
			(layer "B.Fab")
		)
		(fp_line
			(start -0.67945 -0.3048)
			(end -0.67945 0.3048)
			(stroke
				(width 0.1)
				(type default)
			)
			(layer "B.Fab")
		)
		(fp_line
			(start -0.12065 -0.3048)
			(end -0.67945 -0.3048)
			(stroke
				(width 0.1)
				(type default)
			)
			(layer "B.Fab")
		)
		(fp_line
			(start 0.12065 -0.305054)
			(end 0.12065 -0.2794)
			(stroke
				(width 0.1)
				(type default)
			)
			(layer "B.Fab")
		)
		(fp_line
			(start 0.67945 -0.305054)
			(end 0.12065 -0.305054)
			(stroke
				(width 0.1)
				(type default)
			)
			(layer "B.Fab")
		)
		(pad "1" smd circle
			(at 0.40005 0 90)
			(size 0 0)
			(layers "B.Cu" "B.Mask" "B.Paste")
			(net "P0V8_SERDES_VDDA_PEX0")
		)
		(pad "2" smd circle
			(at -0.40005 0 90)
			(size 0 0)
			(layers "B.Cu" "B.Mask" "B.Paste")
			(net "P0V8_SERDES_VDDA_PEX0_C6")
		)
	)
	(footprint ""
		(layer "B.Cu")
		(at 353.422204 -221.238572 180)
		(property "Reference" "C2061"
			(at 0 0 0)
			(layer "B.SilkS")
			(hide yes)
			(effects
				(font
					(size 1.27 1.27)
				)
				(justify mirror)
			)
		)
		(property "Value" ""
			(at 0 0 0)
			(layer "B.Fab")
			(effects
				(font
					(size 1.27 1.27)
				)
				(justify mirror)
			)
		)
		(duplicate_pad_numbers_are_jumpers no)
		(fp_line
			(start 0.69215 0.2921)
			(end 0.69215 -0.2921)
			(stroke
				(width 0.1524)
				(type default)
			)
			(layer "B.SilkS")
		)
		(fp_line
			(start 0.69215 -0.2921)
			(end -0.69215 -0.2921)
			(stroke
				(width 0.1524)
				(type default)
			)
			(layer "B.SilkS")
		)
		(fp_line
			(start -0.69215 0.2921)
			(end 0.69215 0.2921)
			(stroke
				(width 0.1524)
				(type default)
			)
			(layer "B.SilkS")
		)
		(fp_line
			(start -0.69215 -0.2921)
			(end -0.69215 0.2921)
			(stroke
				(width 0.1524)
				(type default)
			)
			(layer "B.SilkS")
		)
		(fp_line
			(start 0.51435 0.2794)
			(end 0.51435 -0.2794)
			(stroke
				(width 0.1)
				(type default)
			)
			(layer "B.Fab")
		)
		(fp_line
			(start 0.51435 -0.2794)
			(end -0.51435 -0.2794)
			(stroke
				(width 0.1)
				(type default)
			)
			(layer "B.Fab")
		)
		(fp_line
			(start -0.51435 0.2794)
			(end 0.51435 0.2794)
			(stroke
				(width 0.1)
				(type default)
			)
			(layer "B.Fab")
		)
		(fp_line
			(start -0.51435 -0.2794)
			(end -0.51435 0.2794)
			(stroke
				(width 0.1)
				(type default)
			)
			(layer "B.Fab")
		)
		(pad "1" smd circle
			(at 0.40005 0)
			(size 0 0)
			(layers "B.Cu" "B.Mask" "B.Paste")
			(net "P3V3_VCC_FPGA_CORE")
		)
		(pad "2" smd circle
			(at -0.40005 0)
			(size 0 0)
			(layers "B.Cu" "B.Mask" "B.Paste")
			(net "GND")
		)
		(zone
			(layer "B.Cu")
			(hatch none 0.5)
			(connect_pads
				(clearance 0)
			)
			(min_thickness 0.25)
			(keepout
				(tracks not_allowed)
				(vias allowed)
				(pads allowed)
				(copperpour not_allowed)
				(footprints allowed)
			)
			(placement
				(enabled no)
				(sheetname "")
			)
			(fill
				(thermal_gap 0.5)
				(thermal_bridge_width 0.5)
				(island_removal_mode 0)
			)
			(polygon
				(pts
					(xy 353.231704 -221.326202) (xy 353.323144 -221.384368) (xy 353.522534 -221.384368) (xy 353.612704 -221.326202)
					(xy 353.612704 -221.150942) (xy 353.522534 -221.092522) (xy 353.323144 -221.092522) (xy 353.231704 -221.150688)
				)
			)
		)
	)
	(footprint ""
		(layer "B.Cu")
		(at 105.021126 -303.649634 -90)
		(property "Reference" "PC70"
			(at 0 0 90)
			(layer "B.SilkS")
			(hide yes)
			(effects
				(font
					(size 1.27 1.27)
				)
				(justify mirror)
			)
		)
		(property "Value" ""
			(at 0 0 90)
			(layer "B.Fab")
			(effects
				(font
					(size 1.27 1.27)
				)
				(justify mirror)
			)
		)
		(duplicate_pad_numbers_are_jumpers no)
		(fp_line
			(start -1.524 0.762)
			(end 1.524 0.762)
			(stroke
				(width 0.1524)
				(type default)
			)
			(layer "B.SilkS")
		)
		(fp_line
			(start 1.524 0.762)
			(end 1.524 -0.762)
			(stroke
				(width 0.1524)
				(type default)
			)
			(layer "B.SilkS")
		)
		(fp_line
			(start -1.524 -0.762)
			(end -1.524 0.762)
			(stroke
				(width 0.1524)
				(type default)
			)
			(layer "B.SilkS")
		)
		(fp_line
			(start 1.524 -0.762)
			(end -1.524 -0.762)
			(stroke
				(width 0.1524)
				(type default)
			)
			(layer "B.SilkS")
		)
		(fp_line
			(start -1.1049 0.724916)
			(end -1.1049 -0.724916)
			(stroke
				(width 0.1)
				(type default)
			)
			(layer "B.Fab")
		)
		(fp_line
			(start 1.1049 0.724916)
			(end -1.1049 0.724916)
			(stroke
				(width 0.1)
				(type default)
			)
			(layer "B.Fab")
		)
		(fp_line
			(start -1.1049 -0.724916)
			(end 1.1049 -0.724916)
			(stroke
				(width 0.1)
				(type default)
			)
			(layer "B.Fab")
		)
		(fp_line
			(start 1.1049 -0.724916)
			(end 1.1049 0.724916)
			(stroke
				(width 0.1)
				(type default)
			)
			(layer "B.Fab")
		)
		(pad "1" smd rect
			(at 0.889 0 270)
			(size 1.016 1.27)
			(layers "B.Cu" "B.Mask" "B.Paste")
			(net "P0V8_PEX0")
		)
		(pad "2" smd rect
			(at -0.889 0 270)
			(size 1.016 1.27)
			(layers "B.Cu" "B.Mask" "B.Paste")
			(net "GND")
		)
	)
	(footprint ""
		(layer "B.Cu")
		(at 336.671412 -323.15531 -90)
		(property "Reference" "R6515"
			(at 0 0 90)
			(layer "B.SilkS")
			(hide yes)
			(effects
				(font
					(size 1.27 1.27)
				)
				(justify mirror)
			)
		)
		(property "Value" ""
			(at 0 0 90)
			(layer "B.Fab")
			(effects
				(font
					(size 1.27 1.27)
				)
				(justify mirror)
			)
		)
		(duplicate_pad_numbers_are_jumpers no)
		(fp_line
			(start -0.7874 0.4064)
			(end 0.7874 0.4064)
			(stroke
				(width 0.1524)
				(type default)
			)
			(layer "B.SilkS")
		)
		(fp_line
			(start 0.7874 0.4064)
			(end 0.7874 -0.4064)
			(stroke
				(width 0.1524)
				(type default)
			)
			(layer "B.SilkS")
		)
		(fp_line
			(start -0.7874 -0.4064)
			(end -0.7874 0.4064)
			(stroke
				(width 0.1524)
				(type default)
			)
			(layer "B.SilkS")
		)
		(fp_line
			(start 0.7874 -0.4064)
			(end -0.7874 -0.4064)
			(stroke
				(width 0.1524)
				(type default)
			)
			(layer "B.SilkS")
		)
		(fp_line
			(start -0.67945 0.3048)
			(end -0.120396 0.3048)
			(stroke
				(width 0.1)
				(type default)
			)
			(layer "B.Fab")
		)
		(fp_line
			(start -0.120396 0.3048)
			(end -0.120396 0.2794)
			(stroke
				(width 0.1)
				(type default)
			)
			(layer "B.Fab")
		)
		(fp_line
			(start 0.12065 0.3048)
			(end 0.67945 0.3048)
			(stroke
				(width 0.1)
				(type default)
			)
			(layer "B.Fab")
		)
		(fp_line
			(start 0.67945 0.3048)
			(end 0.67945 -0.305054)
			(stroke
				(width 0.1)
				(type default)
			)
			(layer "B.Fab")
		)
		(fp_line
			(start -0.120396 0.2794)
			(end 0.12065 0.2794)
			(stroke
				(width 0.1)
				(type default)
			)
			(layer "B.Fab")
		)
		(fp_line
			(start 0.12065 0.2794)
			(end 0.12065 0.3048)
			(stroke
				(width 0.1)
				(type default)
			)
			(layer "B.Fab")
		)
		(fp_line
			(start -0.12065 -0.2794)
			(end -0.12065 -0.3048)
			(stroke
				(width 0.1)
				(type default)
			)
			(layer "B.Fab")
		)
		(fp_line
			(start 0.12065 -0.2794)
			(end -0.12065 -0.2794)
			(stroke
				(width 0.1)
				(type default)
			)
			(layer "B.Fab")
		)
		(fp_line
			(start -0.67945 -0.3048)
			(end -0.67945 0.3048)
			(stroke
				(width 0.1)
				(type default)
			)
			(layer "B.Fab")
		)
		(fp_line
			(start -0.12065 -0.3048)
			(end -0.67945 -0.3048)
			(stroke
				(width 0.1)
				(type default)
			)
			(layer "B.Fab")
		)
		(fp_line
			(start 0.12065 -0.305054)
			(end 0.12065 -0.2794)
			(stroke
				(width 0.1)
				(type default)
			)
			(layer "B.Fab")
		)
		(fp_line
			(start 0.67945 -0.305054)
			(end 0.12065 -0.305054)
			(stroke
				(width 0.1)
				(type default)
			)
			(layer "B.Fab")
		)
		(pad "1" smd circle
			(at 0.40005 0 90)
			(size 0 0)
			(layers "B.Cu" "B.Mask" "B.Paste")
			(net "P0V8_SERDES_VDDA_PEX2")
		)
		(pad "2" smd circle
			(at -0.40005 0 90)
			(size 0 0)
			(layers "B.Cu" "B.Mask" "B.Paste")
			(net "P0V8_SERDES_VDDA_PEX2_C8")
		)
	)
	(footprint ""
		(layer "B.Cu")
		(at 237.631986 -357.130858)
		(property "Reference" "PR7148"
			(at 0 0 0)
			(layer "B.SilkS")
			(hide yes)
			(effects
				(font
					(size 1.27 1.27)
				)
				(justify mirror)
			)
		)
		(property "Value" ""
			(at 0 0 0)
			(layer "B.Fab")
			(effects
				(font
					(size 1.27 1.27)
				)
				(justify mirror)
			)
		)
		(duplicate_pad_numbers_are_jumpers no)
		(fp_line
			(start -0.7874 -0.4064)
			(end -0.7874 0.4064)
			(stroke
				(width 0.1524)
				(type default)
			)
			(layer "B.SilkS")
		)
		(fp_line
			(start -0.7874 0.4064)
			(end 0.7874 0.4064)
			(stroke
				(width 0.1524)
				(type default)
			)
			(layer "B.SilkS")
		)
		(fp_line
			(start 0.7874 -0.4064)
			(end -0.7874 -0.4064)
			(stroke
				(width 0.1524)
				(type default)
			)
			(layer "B.SilkS")
		)
		(fp_line
			(start 0.7874 0.4064)
			(end 0.7874 -0.4064)
			(stroke
				(width 0.1524)
				(type default)
			)
			(layer "B.SilkS")
		)
		(fp_line
			(start -0.67945 -0.3048)
			(end -0.67945 0.3048)
			(stroke
				(width 0.1)
				(type default)
			)
			(layer "B.Fab")
		)
		(fp_line
			(start -0.67945 0.3048)
			(end -0.120396 0.3048)
			(stroke
				(width 0.1)
				(type default)
			)
			(layer "B.Fab")
		)
		(fp_line
			(start -0.12065 -0.3048)
			(end -0.67945 -0.3048)
			(stroke
				(width 0.1)
				(type default)
			)
			(layer "B.Fab")
		)
		(fp_line
			(start -0.12065 -0.2794)
			(end -0.12065 -0.3048)
			(stroke
				(width 0.1)
				(type default)
			)
			(layer "B.Fab")
		)
		(fp_line
			(start -0.120396 0.2794)
			(end 0.12065 0.2794)
			(stroke
				(width 0.1)
				(type default)
			)
			(layer "B.Fab")
		)
		(fp_line
			(start -0.120396 0.3048)
			(end -0.120396 0.2794)
			(stroke
				(width 0.1)
				(type default)
			)
			(layer "B.Fab")
		)
		(fp_line
			(start 0.12065 -0.305054)
			(end 0.12065 -0.2794)
			(stroke
				(width 0.1)
				(type default)
			)
			(layer "B.Fab")
		)
		(fp_line
			(start 0.12065 -0.2794)
			(end -0.12065 -0.2794)
			(stroke
				(width 0.1)
				(type default)
			)
			(layer "B.Fab")
		)
		(fp_line
			(start 0.12065 0.2794)
			(end 0.12065 0.3048)
			(stroke
				(width 0.1)
				(type default)
			)
			(layer "B.Fab")
		)
		(fp_line
			(start 0.12065 0.3048)
			(end 0.67945 0.3048)
			(stroke
				(width 0.1)
				(type default)
			)
			(layer "B.Fab")
		)
		(fp_line
			(start 0.67945 -0.305054)
			(end 0.12065 -0.305054)
			(stroke
				(width 0.1)
				(type default)
			)
			(layer "B.Fab")
		)
		(fp_line
			(start 0.67945 0.3048)
			(end 0.67945 -0.305054)
			(stroke
				(width 0.1)
				(type default)
			)
			(layer "B.Fab")
		)
		(pad "1" smd circle
			(at 0.40005 0 180)
			(size 0 0)
			(layers "B.Cu" "B.Mask" "B.Paste")
			(net "P12V_HSC_ADC_P")
		)
		(pad "2" smd circle
			(at -0.40005 0 180)
			(size 0 0)
			(layers "B.Cu" "B.Mask" "B.Paste")
			(net "P12V_HSC_SENSE2_R2_P")
		)
	)
	(footprint ""
		(layer "B.Cu")
		(at 228.651054 -291.888926 180)
		(property "Reference" "PC993"
			(at 0 0 0)
			(layer "B.SilkS")
			(hide yes)
			(effects
				(font
					(size 1.27 1.27)
				)
				(justify mirror)
			)
		)
		(property "Value" ""
			(at 0 0 0)
			(layer "B.Fab")
			(effects
				(font
					(size 1.27 1.27)
				)
				(justify mirror)
			)
		)
		(duplicate_pad_numbers_are_jumpers no)
		(fp_line
			(start 1.524 0.762)
			(end 1.524 -0.762)
			(stroke
				(width 0.1524)
				(type default)
			)
			(layer "B.SilkS")
		)
		(fp_line
			(start 1.524 -0.762)
			(end -1.524 -0.762)
			(stroke
				(width 0.1524)
				(type default)
			)
			(layer "B.SilkS")
		)
		(fp_line
			(start -1.524 0.762)
			(end 1.524 0.762)
			(stroke
				(width 0.1524)
				(type default)
			)
			(layer "B.SilkS")
		)
		(fp_line
			(start -1.524 -0.762)
			(end -1.524 0.762)
			(stroke
				(width 0.1524)
				(type default)
			)
			(layer "B.SilkS")
		)
		(fp_line
			(start 1.1049 0.724916)
			(end -1.1049 0.724916)
			(stroke
				(width 0.1)
				(type default)
			)
			(layer "B.Fab")
		)
		(fp_line
			(start 1.1049 -0.724916)
			(end 1.1049 0.724916)
			(stroke
				(width 0.1)
				(type default)
			)
			(layer "B.Fab")
		)
		(fp_line
			(start -1.1049 0.724916)
			(end -1.1049 -0.724916)
			(stroke
				(width 0.1)
				(type default)
			)
			(layer "B.Fab")
		)
		(fp_line
			(start -1.1049 -0.724916)
			(end 1.1049 -0.724916)
			(stroke
				(width 0.1)
				(type default)
			)
			(layer "B.Fab")
		)
		(pad "1" smd rect
			(at 0.889 0 180)
			(size 1.016 1.27)
			(layers "B.Cu" "B.Mask" "B.Paste")
			(net "P1V25_PEX1_R")
		)
		(pad "2" smd rect
			(at -0.889 0 180)
			(size 1.016 1.27)
			(layers "B.Cu" "B.Mask" "B.Paste")
			(net "GND")
		)
	)
	(footprint ""
		(layer "B.Cu")
		(at 52.999894 -292.099746 90)
		(property "Reference" "C1188"
			(at 0 0 90)
			(layer "B.SilkS")
			(hide yes)
			(effects
				(font
					(size 1.27 1.27)
				)
				(justify mirror)
			)
		)
		(property "Value" ""
			(at 0 0 90)
			(layer "B.Fab")
			(effects
				(font
					(size 1.27 1.27)
				)
				(justify mirror)
			)
		)
		(duplicate_pad_numbers_are_jumpers no)
		(fp_line
			(start 0.299974 -0.150114)
			(end -0.299974 -0.150114)
			(stroke
				(width 0.1)
				(type default)
			)
			(layer "B.Fab")
		)
		(fp_line
			(start -0.299974 -0.150114)
			(end -0.299974 0.150114)
			(stroke
				(width 0.1)
				(type default)
			)
			(layer "B.Fab")
		)
		(fp_line
			(start 0.299974 0.150114)
			(end 0.299974 -0.150114)
			(stroke
				(width 0.1)
				(type default)
			)
			(layer "B.Fab")
		)
		(fp_line
			(start -0.299974 0.150114)
			(end 0.299974 0.150114)
			(stroke
				(width 0.1)
				(type default)
			)
			(layer "B.Fab")
		)
		(pad "1" smd rect
			(at 0.2667 0 270)
			(size 0.3048 0.381)
			(layers "B.Cu" "B.Mask" "B.Paste")
			(net "P0V8_SERDES_VDDA_PEX0")
		)
		(pad "2" smd rect
			(at -0.2667 0 270)
			(size 0.3048 0.381)
			(layers "B.Cu" "B.Mask" "B.Paste")
			(net "GND")
		)
	)
)
